(kicad_pcb
	(version 20260206)
	(generator "pcbnew")
	(generator_version "10.0")
	(general
		(thickness 1.6)
		(legacy_teardrops no)
	)
	(paper "A4")
	(title_block
		(title "04192023_DAF0TMB3IC0_F0TG_MB_C_brd_V02_OCP.brd")
		(comment 1 "Grand Teton / footprints 5264-5271 of 8354")
	)
	(layers
		(0 "F.Cu" signal "TOP")
		(4 "In1.Cu" signal "GND")
		(6 "In2.Cu" signal "IN1")
		(8 "In3.Cu" signal "GND1")
		(10 "In4.Cu" signal "IN2")
		(12 "In5.Cu" signal "GND2")
		(14 "In6.Cu" signal "IN3")
		(16 "In7.Cu" signal "GND3")
		(18 "In8.Cu" signal "VCC")
		(20 "In9.Cu" signal "VCC1")
		(22 "In10.Cu" signal "GND4")
		(24 "In11.Cu" signal "IN4")
		(26 "In12.Cu" signal "GND5")
		(28 "In13.Cu" signal "IN5")
		(30 "In14.Cu" signal "GND6")
		(32 "In15.Cu" signal "IN6")
		(34 "In16.Cu" signal "GND7")
		(2 "B.Cu" signal "BOTTOM")
		(9 "F.Adhes" user "F.Adhesive")
		(11 "B.Adhes" user "B.Adhesive")
		(13 "F.Paste" user "Package Geometry/Pastemask Top")
		(15 "B.Paste" user "Package Geometry/Pastemask Bottom")
		(5 "F.SilkS" user "Ref Des/Silkscreen Top")
		(7 "B.SilkS" user "Ref Des/Silkscreen Bottom")
		(1 "F.Mask" user "Board Geometry/Soldermask Top")
		(3 "B.Mask" user "Board Geometry/Soldermask Bottom")
		(17 "Dwgs.User" user "User.Drawings")
		(19 "Cmts.User" user "User.Comments")
		(21 "Eco1.User" user "User.Eco1")
		(23 "Eco2.User" user "User.Eco2")
		(25 "Edge.Cuts" user "Board Geometry/Outline")
		(27 "Margin" user)
		(31 "F.CrtYd" user "Package Geometry/Place Bound Top")
		(29 "B.CrtYd" user "Package Geometry/Place Bound Bottom")
		(35 "F.Fab" user "Ref Des/Assembly Top")
		(33 "B.Fab" user "Ref Des/Assembly Bottom")
	)
	(footprint ""
		(layer "B.Cu")
		(at 339.506052 -395.148562 90)
		(property "Reference" "C607"
			(at 0 0 90)
			(layer "B.SilkS")
			(hide yes)
			(effects
				(font
					(size 1.27 1.27)
				)
				(justify mirror)
			)
		)
		(property "Value" ""
			(at 0 0 90)
			(layer "B.Fab")
			(effects
				(font
					(size 1.27 1.27)
				)
				(justify mirror)
			)
		)
		(duplicate_pad_numbers_are_jumpers no)
		(fp_line
			(start 0.299974 -0.150114)
			(end -0.299974 -0.150114)
			(stroke
				(width 0.1)
				(type default)
			)
			(layer "B.Fab")
		)
		(fp_line
			(start -0.299974 -0.150114)
			(end -0.299974 0.150114)
			(stroke
				(width 0.1)
				(type default)
			)
			(layer "B.Fab")
		)
		(fp_line
			(start 0.299974 0.150114)
			(end 0.299974 -0.150114)
			(stroke
				(width 0.1)
				(type default)
			)
			(layer "B.Fab")
		)
		(fp_line
			(start -0.299974 0.150114)
			(end 0.299974 0.150114)
			(stroke
				(width 0.1)
				(type default)
			)
			(layer "B.Fab")
		)
		(pad "1" smd rect
			(at 0.2667 0 270)
			(size 0.3048 0.381)
			(layers "B.Cu" "B.Mask" "B.Paste")
			(net "P0V9_CPU0_RT1_2A")
		)
		(pad "2" smd rect
			(at -0.2667 0 270)
			(size 0.3048 0.381)
			(layers "B.Cu" "B.Mask" "B.Paste")
			(net "GND")
		)
	)
	(footprint ""
		(layer "B.Cu")
		(at 164.465 -426.4152 -90)
		(property "Reference" "R1430"
			(at 0 0 90)
			(layer "B.SilkS")
			(hide yes)
			(effects
				(font
					(size 1.27 1.27)
				)
				(justify mirror)
			)
		)
		(property "Value" ""
			(at 0 0 90)
			(layer "B.Fab")
			(effects
				(font
					(size 1.27 1.27)
				)
				(justify mirror)
			)
		)
		(duplicate_pad_numbers_are_jumpers no)
		(fp_line
			(start -0.32512 0.175006)
			(end 0.32512 0.175006)
			(stroke
				(width 0.1)
				(type default)
			)
			(layer "B.Fab")
		)
		(fp_line
			(start 0.32512 0.175006)
			(end 0.32512 -0.175006)
			(stroke
				(width 0.1)
				(type default)
			)
			(layer "B.Fab")
		)
		(fp_line
			(start -0.32512 -0.175006)
			(end -0.32512 0.175006)
			(stroke
				(width 0.1)
				(type default)
			)
			(layer "B.Fab")
		)
		(fp_line
			(start 0.32512 -0.175006)
			(end -0.32512 -0.175006)
			(stroke
				(width 0.1)
				(type default)
			)
			(layer "B.Fab")
		)
		(pad "1" smd rect
			(at 0.2667 0 90)
			(size 0.3048 0.381)
			(layers "B.Cu" "B.Mask" "B.Paste")
			(net "JTAG_TCK_RT_CPU1_P3")
		)
		(pad "2" smd rect
			(at -0.2667 0 270)
			(size 0.3048 0.381)
			(layers "B.Cu" "B.Mask" "B.Paste")
			(net "GND")
		)
	)
	(footprint ""
		(layer "B.Cu")
		(at 309.518304 -396.393162 -90)
		(property "Reference" "C522"
			(at 0 0 90)
			(layer "B.SilkS")
			(hide yes)
			(effects
				(font
					(size 1.27 1.27)
				)
				(justify mirror)
			)
		)
		(property "Value" ""
			(at 0 0 90)
			(layer "B.Fab")
			(effects
				(font
					(size 1.27 1.27)
				)
				(justify mirror)
			)
		)
		(duplicate_pad_numbers_are_jumpers no)
		(fp_line
			(start -0.299974 0.150114)
			(end 0.299974 0.150114)
			(stroke
				(width 0.1)
				(type default)
			)
			(layer "B.Fab")
		)
		(fp_line
			(start 0.299974 0.150114)
			(end 0.299974 -0.150114)
			(stroke
				(width 0.1)
				(type default)
			)
			(layer "B.Fab")
		)
		(fp_line
			(start -0.299974 -0.150114)
			(end -0.299974 0.150114)
			(stroke
				(width 0.1)
				(type default)
			)
			(layer "B.Fab")
		)
		(fp_line
			(start 0.299974 -0.150114)
			(end -0.299974 -0.150114)
			(stroke
				(width 0.1)
				(type default)
			)
			(layer "B.Fab")
		)
		(pad "1" smd rect
			(at 0.2667 0 90)
			(size 0.3048 0.381)
			(layers "B.Cu" "B.Mask" "B.Paste")
			(net "P0V9_CPU0_RT_2D")
		)
		(pad "2" smd rect
			(at -0.2667 0 90)
			(size 0.3048 0.381)
			(layers "B.Cu" "B.Mask" "B.Paste")
			(net "GND")
		)
	)
	(footprint ""
		(layer "B.Cu")
		(at 213.79688 -54.447948 90)
		(property "Reference" "R3751"
			(at 0 0 90)
			(layer "B.SilkS")
			(hide yes)
			(effects
				(font
					(size 1.27 1.27)
				)
				(justify mirror)
			)
		)
		(property "Value" ""
			(at 0 0 90)
			(layer "B.Fab")
			(effects
				(font
					(size 1.27 1.27)
				)
				(justify mirror)
			)
		)
		(duplicate_pad_numbers_are_jumpers no)
		(fp_line
			(start 0.7874 -0.4064)
			(end -0.7874 -0.4064)
			(stroke
				(width 0.1524)
				(type default)
			)
			(layer "B.SilkS")
		)
		(fp_line
			(start -0.7874 -0.4064)
			(end -0.7874 0.4064)
			(stroke
				(width 0.1524)
				(type default)
			)
			(layer "B.SilkS")
		)
		(fp_line
			(start 0.7874 0.4064)
			(end 0.7874 -0.4064)
			(stroke
				(width 0.1524)
				(type default)
			)
			(layer "B.SilkS")
		)
		(fp_line
			(start -0.7874 0.4064)
			(end 0.7874 0.4064)
			(stroke
				(width 0.1524)
				(type default)
			)
			(layer "B.SilkS")
		)
		(fp_line
			(start 0.67945 -0.305054)
			(end 0.12065 -0.305054)
			(stroke
				(width 0.1)
				(type default)
			)
			(layer "B.Fab")
		)
		(fp_line
			(start 0.12065 -0.305054)
			(end 0.12065 -0.2794)
			(stroke
				(width 0.1)
				(type default)
			)
			(layer "B.Fab")
		)
		(fp_line
			(start -0.12065 -0.3048)
			(end -0.67945 -0.3048)
			(stroke
				(width 0.1)
				(type default)
			)
			(layer "B.Fab")
		)
		(fp_line
			(start -0.67945 -0.3048)
			(end -0.67945 0.3048)
			(stroke
				(width 0.1)
				(type default)
			)
			(layer "B.Fab")
		)
		(fp_line
			(start 0.12065 -0.2794)
			(end -0.12065 -0.2794)
			(stroke
				(width 0.1)
				(type default)
			)
			(layer "B.Fab")
		)
		(fp_line
			(start -0.12065 -0.2794)
			(end -0.12065 -0.3048)
			(stroke
				(width 0.1)
				(type default)
			)
			(layer "B.Fab")
		)
		(fp_line
			(start 0.12065 0.2794)
			(end 0.12065 0.3048)
			(stroke
				(width 0.1)
				(type default)
			)
			(layer "B.Fab")
		)
		(fp_line
			(start -0.120396 0.2794)
			(end 0.12065 0.2794)
			(stroke
				(width 0.1)
				(type default)
			)
			(layer "B.Fab")
		)
		(fp_line
			(start 0.67945 0.3048)
			(end 0.67945 -0.305054)
			(stroke
				(width 0.1)
				(type default)
			)
			(layer "B.Fab")
		)
		(fp_line
			(start 0.12065 0.3048)
			(end 0.67945 0.3048)
			(stroke
				(width 0.1)
				(type default)
			)
			(layer "B.Fab")
		)
		(fp_line
			(start -0.120396 0.3048)
			(end -0.120396 0.2794)
			(stroke
				(width 0.1)
				(type default)
			)
			(layer "B.Fab")
		)
		(fp_line
			(start -0.67945 0.3048)
			(end -0.120396 0.3048)
			(stroke
				(width 0.1)
				(type default)
			)
			(layer "B.Fab")
		)
		(pad "1" smd circle
			(at 0.40005 0 270)
			(size 0 0)
			(layers "B.Cu" "B.Mask" "B.Paste")
			(net "INA230_2_A0")
		)
		(pad "2" smd circle
			(at -0.40005 0 270)
			(size 0 0)
			(layers "B.Cu" "B.Mask" "B.Paste")
			(net "SMB_INA230_2_3V3AUX_SDA_R1")
		)
	)
	(footprint ""
		(layer "B.Cu")
		(at 265.506454 -190.82131 180)
		(property "Reference" "R296"
			(at 0 0 0)
			(layer "B.SilkS")
			(hide yes)
			(effects
				(font
					(size 1.27 1.27)
				)
				(justify mirror)
			)
		)
		(property "Value" ""
			(at 0 0 0)
			(layer "B.Fab")
			(effects
				(font
					(size 1.27 1.27)
				)
				(justify mirror)
			)
		)
		(duplicate_pad_numbers_are_jumpers no)
		(fp_line
			(start 0.7874 0.4064)
			(end 0.7874 -0.4064)
			(stroke
				(width 0.1524)
				(type default)
			)
			(layer "B.SilkS")
		)
		(fp_line
			(start 0.7874 -0.4064)
			(end -0.7874 -0.4064)
			(stroke
				(width 0.1524)
				(type default)
			)
			(layer "B.SilkS")
		)
		(fp_line
			(start -0.7874 0.4064)
			(end 0.7874 0.4064)
			(stroke
				(width 0.1524)
				(type default)
			)
			(layer "B.SilkS")
		)
		(fp_line
			(start -0.7874 -0.4064)
			(end -0.7874 0.4064)
			(stroke
				(width 0.1524)
				(type default)
			)
			(layer "B.SilkS")
		)
		(fp_line
			(start 0.67945 0.3048)
			(end 0.67945 -0.305054)
			(stroke
				(width 0.1)
				(type default)
			)
			(layer "B.Fab")
		)
		(fp_line
			(start 0.67945 -0.305054)
			(end 0.12065 -0.305054)
			(stroke
				(width 0.1)
				(type default)
			)
			(layer "B.Fab")
		)
		(fp_line
			(start 0.12065 0.3048)
			(end 0.67945 0.3048)
			(stroke
				(width 0.1)
				(type default)
			)
			(layer "B.Fab")
		)
		(fp_line
			(start 0.12065 0.2794)
			(end 0.12065 0.3048)
			(stroke
				(width 0.1)
				(type default)
			)
			(layer "B.Fab")
		)
		(fp_line
			(start 0.12065 -0.2794)
			(end -0.12065 -0.2794)
			(stroke
				(width 0.1)
				(type default)
			)
			(layer "B.Fab")
		)
		(fp_line
			(start 0.12065 -0.305054)
			(end 0.12065 -0.2794)
			(stroke
				(width 0.1)
				(type default)
			)
			(layer "B.Fab")
		)
		(fp_line
			(start -0.120396 0.3048)
			(end -0.120396 0.2794)
			(stroke
				(width 0.1)
				(type default)
			)
			(layer "B.Fab")
		)
		(fp_line
			(start -0.120396 0.2794)
			(end 0.12065 0.2794)
			(stroke
				(width 0.1)
				(type default)
			)
			(layer "B.Fab")
		)
		(fp_line
			(start -0.12065 -0.2794)
			(end -0.12065 -0.3048)
			(stroke
				(width 0.1)
				(type default)
			)
			(layer "B.Fab")
		)
		(fp_line
			(start -0.12065 -0.3048)
			(end -0.67945 -0.3048)
			(stroke
				(width 0.1)
				(type default)
			)
			(layer "B.Fab")
		)
		(fp_line
			(start -0.67945 0.3048)
			(end -0.120396 0.3048)
			(stroke
				(width 0.1)
				(type default)
			)
			(layer "B.Fab")
		)
		(fp_line
			(start -0.67945 -0.3048)
			(end -0.67945 0.3048)
			(stroke
				(width 0.1)
				(type default)
			)
			(layer "B.Fab")
		)
		(pad "1" smd circle
			(at 0.40005 0)
			(size 0 0)
			(layers "B.Cu" "B.Mask" "B.Paste")
			(net "PWRGD_CHF_CPU0_DIMM")
		)
		(pad "2" smd circle
			(at -0.40005 0)
			(size 0 0)
			(layers "B.Cu" "B.Mask" "B.Paste")
			(net "PWRGD_CHAF_CPU0")
		)
	)
	(footprint ""
		(layer "B.Cu")
		(at 299.265594 -392.66876 180)
		(property "Reference" "R984"
			(at 0 0 0)
			(layer "B.SilkS")
			(hide yes)
			(effects
				(font
					(size 1.27 1.27)
				)
				(justify mirror)
			)
		)
		(property "Value" ""
			(at 0 0 0)
			(layer "B.Fab")
			(effects
				(font
					(size 1.27 1.27)
				)
				(justify mirror)
			)
		)
		(duplicate_pad_numbers_are_jumpers no)
		(fp_line
			(start 0.32512 0.175006)
			(end 0.32512 -0.175006)
			(stroke
				(width 0.1)
				(type default)
			)
			(layer "B.Fab")
		)
		(fp_line
			(start 0.32512 -0.175006)
			(end -0.32512 -0.175006)
			(stroke
				(width 0.1)
				(type default)
			)
			(layer "B.Fab")
		)
		(fp_line
			(start -0.32512 0.175006)
			(end 0.32512 0.175006)
			(stroke
				(width 0.1)
				(type default)
			)
			(layer "B.Fab")
		)
		(fp_line
			(start -0.32512 -0.175006)
			(end -0.32512 0.175006)
			(stroke
				(width 0.1)
				(type default)
			)
			(layer "B.Fab")
		)
		(pad "1" smd rect
			(at 0.2667 0)
			(size 0.3048 0.381)
			(layers "B.Cu" "B.Mask" "B.Paste")
			(net "TEST1_RT_CPU0_P0")
		)
		(pad "2" smd rect
			(at -0.2667 0 180)
			(size 0.3048 0.381)
			(layers "B.Cu" "B.Mask" "B.Paste")
			(net "GND")
		)
	)
	(footprint ""
		(layer "B.Cu")
		(at 139.34694 -13.52169 -90)
		(property "Reference" "R4809"
			(at 0 0 90)
			(layer "B.SilkS")
			(hide yes)
			(effects
				(font
					(size 1.27 1.27)
				)
				(justify mirror)
			)
		)
		(property "Value" ""
			(at 0 0 90)
			(layer "B.Fab")
			(effects
				(font
					(size 1.27 1.27)
				)
				(justify mirror)
			)
		)
		(duplicate_pad_numbers_are_jumpers no)
		(fp_line
			(start -0.7874 0.4064)
			(end 0.7874 0.4064)
			(stroke
				(width 0.1524)
				(type default)
			)
			(layer "B.SilkS")
		)
		(fp_line
			(start 0.7874 0.4064)
			(end 0.7874 -0.4064)
			(stroke
				(width 0.1524)
				(type default)
			)
			(layer "B.SilkS")
		)
		(fp_line
			(start -0.7874 -0.4064)
			(end -0.7874 0.4064)
			(stroke
				(width 0.1524)
				(type default)
			)
			(layer "B.SilkS")
		)
		(fp_line
			(start 0.7874 -0.4064)
			(end -0.7874 -0.4064)
			(stroke
				(width 0.1524)
				(type default)
			)
			(layer "B.SilkS")
		)
		(fp_line
			(start -0.67945 0.3048)
			(end -0.120396 0.3048)
			(stroke
				(width 0.1)
				(type default)
			)
			(layer "B.Fab")
		)
		(fp_line
			(start -0.120396 0.3048)
			(end -0.120396 0.2794)
			(stroke
				(width 0.1)
				(type default)
			)
			(layer "B.Fab")
		)
		(fp_line
			(start 0.12065 0.3048)
			(end 0.67945 0.3048)
			(stroke
				(width 0.1)
				(type default)
			)
			(layer "B.Fab")
		)
		(fp_line
			(start 0.67945 0.3048)
			(end 0.67945 -0.305054)
			(stroke
				(width 0.1)
				(type default)
			)
			(layer "B.Fab")
		)
		(fp_line
			(start -0.120396 0.2794)
			(end 0.12065 0.2794)
			(stroke
				(width 0.1)
				(type default)
			)
			(layer "B.Fab")
		)
		(fp_line
			(start 0.12065 0.2794)
			(end 0.12065 0.3048)
			(stroke
				(width 0.1)
				(type default)
			)
			(layer "B.Fab")
		)
		(fp_line
			(start -0.12065 -0.2794)
			(end -0.12065 -0.3048)
			(stroke
				(width 0.1)
				(type default)
			)
			(layer "B.Fab")
		)
		(fp_line
			(start 0.12065 -0.2794)
			(end -0.12065 -0.2794)
			(stroke
				(width 0.1)
				(type default)
			)
			(layer "B.Fab")
		)
		(fp_line
			(start -0.67945 -0.3048)
			(end -0.67945 0.3048)
			(stroke
				(width 0.1)
				(type default)
			)
			(layer "B.Fab")
		)
		(fp_line
			(start -0.12065 -0.3048)
			(end -0.67945 -0.3048)
			(stroke
				(width 0.1)
				(type default)
			)
			(layer "B.Fab")
		)
		(fp_line
			(start 0.12065 -0.305054)
			(end 0.12065 -0.2794)
			(stroke
				(width 0.1)
				(type default)
			)
			(layer "B.Fab")
		)
		(fp_line
			(start 0.67945 -0.305054)
			(end 0.12065 -0.305054)
			(stroke
				(width 0.1)
				(type default)
			)
			(layer "B.Fab")
		)
		(pad "1" smd circle
			(at 0.40005 0 90)
			(size 0 0)
			(layers "B.Cu" "B.Mask" "B.Paste")
			(net "TP_CHASI")
		)
		(pad "2" smd circle
			(at -0.40005 0 90)
			(size 0 0)
			(layers "B.Cu" "B.Mask" "B.Paste")
			(net "GND")
		)
	)
	(footprint ""
		(layer "B.Cu")
		(at 488.03433 -147.888198 90)
		(property "Reference" "X6"
			(at 1.112012 2.605024 270)
			(unlocked yes)
			(layer "B.SilkS")
			(effects
				(font
					(size 0.7874 0.5842)
					(thickness 0.1524)
				)
				(justify left mirror)
			)
		)
		(property "Value" ""
			(at 0 0 90)
			(layer "B.Fab")
			(effects
				(font
					(size 1.27 1.27)
				)
				(justify mirror)
			)
		)
		(property "Device Type" "TP_TDR_4P_FTS_TH-TP_TDR_4P_DIP,EMPTY,TP15"
			(at -1.30175 1.27 0)
			(unlocked yes)
			(layer "B.Fab")
			(hide yes)
			(effects
				(font
					(size 0.635 0.4064)
					(thickness 0.1524)
				)
				(justify mirror)
			)
		)
		(property "User Part Number" "N_A"
			(at -1.30175 1.27 0)
			(unlocked yes)
			(layer "Cmts.User")
			(hide yes)
			(effects
				(font
					(size 0.635 0.4064)
					(thickness 0.1524)
				)
				(justify mirror)
			)
		)
		(duplicate_pad_numbers_are_jumpers no)
		(fp_line
			(start 0 -1.27)
			(end 0 -0.635)
			(stroke
				(width 0.1524)
				(type default)
			)
			(layer "B.SilkS")
		)
		(fp_line
			(start -2.54 -1.27)
			(end 0 -1.27)
			(stroke
				(width 0.1524)
				(type default)
			)
			(layer "B.SilkS")
		)
		(fp_line
			(start -2.54 -1.1303)
			(end -2.54 -1.27)
			(stroke
				(width 0.1524)
				(type default)
			)
			(layer "B.SilkS")
		)
		(fp_line
			(start 0 0.635)
			(end 0 1.905)
			(stroke
				(width 0.1524)
				(type default)
			)
			(layer "B.SilkS")
		)
		(fp_line
			(start -2.54 1.4097)
			(end -2.54 1.1303)
			(stroke
				(width 0.1524)
				(type default)
			)
			(layer "B.SilkS")
		)
		(fp_line
			(start 0 3.175)
			(end 0 3.81)
			(stroke
				(width 0.1524)
				(type default)
			)
			(layer "B.SilkS")
		)
		(fp_line
			(start 0 3.81)
			(end -2.54 3.81)
			(stroke
				(width 0.1524)
				(type default)
			)
			(layer "B.SilkS")
		)
		(fp_line
			(start -2.54 3.81)
			(end -2.54 3.6703)
			(stroke
				(width 0.1524)
				(type default)
			)
			(layer "B.SilkS")
		)
		(fp_poly
			(pts
				(xy 2.285746 -0.762) (xy 2.285746 0.762) (xy 0.761746 0)
			)
			(stroke
				(width 0)
				(type default)
			)
			(fill yes)
			(layer "B.SilkS")
		)
		(fp_line
			(start 0 -1.27)
			(end 0 3.81)
			(stroke
				(width 0.1)
				(type default)
			)
			(layer "B.Fab")
		)
		(fp_line
			(start -2.54 -1.27)
			(end 0 -1.27)
			(stroke
				(width 0.1)
				(type default)
			)
			(layer "B.Fab")
		)
		(fp_line
			(start 0 3.81)
			(end -2.54 3.81)
			(stroke
				(width 0.1)
				(type default)
			)
			(layer "B.Fab")
		)
		(fp_line
			(start -2.54 3.81)
			(end -2.54 -1.27)
			(stroke
				(width 0.1)
				(type default)
			)
			(layer "B.Fab")
		)
		(fp_poly
			(pts
				(xy 0.761746 0) (xy 2.285746 -0.762) (xy 2.285746 0.762)
			)
			(stroke
				(width 0)
				(type default)
			)
			(fill yes)
			(layer "B.Fab")
		)
		(pad "1" thru_hole circle
			(at 0 0 270)
			(size 1.0033 1.0033)
			(drill 0.249936)
			(layers "*.Cu" "*.Mask")
			(remove_unused_layers no)
			(net "TDR_DIFF_80_BOT_DP")
			(clearance 0.10795)
			(padstack
				(mode front_inner_back)
				(layer "Inner"
					(shape circle)
					(size 0.8001 0.8001)
					(clearance 0.1524)
				)
				(layer "B.Cu"
					(shape circle)
					(size 1.0033 1.0033)
					(thermal_gap 0.10795)
					(clearance 0.10795)
				)
			)
		)
		(pad "2" thru_hole circle
			(at -2.54 0 270)
			(size 1.9939 1.9939)
			(drill 0.249936)
			(layers "*.Cu" "*.Mask")
			(remove_unused_layers no)
			(net "T1_GND")
			(clearance 0.10795)
			(padstack
				(mode front_inner_back)
				(layer "Inner"
					(shape circle)
					(size 0.8001 0.8001)
					(clearance 0.1524)
				)
				(layer "B.Cu"
					(shape circle)
					(size 1.9939 1.9939)
					(thermal_gap 0.10795)
					(clearance 0.10795)
				)
			)
		)
		(pad "3" thru_hole circle
			(at -2.54 2.54 270)
			(size 1.9939 1.9939)
			(drill 0.249936)
			(layers "*.Cu" "*.Mask")
			(remove_unused_layers no)
			(net "T1_GND")
			(clearance 0.10795)
			(padstack
				(mode front_inner_back)
				(layer "Inner"
					(shape circle)
					(size 0.8001 0.8001)
					(clearance 0.1524)
				)
				(layer "B.Cu"
					(shape circle)
					(size 1.9939 1.9939)
					(thermal_gap 0.10795)
					(clearance 0.10795)
				)
			)
		)
		(pad "4" thru_hole circle
			(at 0 2.54 270)
			(size 1.0033 1.0033)
			(drill 0.249936)
			(layers "*.Cu" "*.Mask")
			(remove_unused_layers no)
			(net "TDR_DIFF_80_BOT_DN")
			(clearance 0.10795)
			(padstack
				(mode front_inner_back)
				(layer "Inner"
					(shape circle)
					(size 0.8001 0.8001)
					(clearance 0.1524)
				)
				(layer "B.Cu"
					(shape circle)
					(size 1.0033 1.0033)
					(thermal_gap 0.10795)
					(clearance 0.10795)
				)
			)
		)
	)
)
